# S9S_MB_2U (Grand Teton) — schematic netlist excerpt (pin names and nets, part order shuffled) for the footprints in the layout excerpt that follows; sources: Cadence DE-HDL packaged netlist, KiCad conversion of 03242023_DA0F0TMBIJ0_F0T_Motherboard_J_brd_V01_OCP.brd

PR436  Q_RES  10K 1% EMPTY  pkg 0402LF  page 274 : A = PVCCFA_EHV_CPU0_BTSEN ; B = GND
R3939  Q_RES  0 5% EMPTY  pkg 0402LF  page 250 : A = P12V_E1S_0_ISENSE_MAM_MAM ; B = P12V_E1S_0_ISENSE_MAM
PC1  Q_CAP  22UF 4V 20% X6S  pkg C0805  page 279 : A = PVCCD_HV_CPU0 ; B = GND

(kicad_pcb
	(version 20260206)
	(generator "pcbnew")
	(generator_version "10.0")
	(general
		(thickness 1.6)
		(legacy_teardrops no)
	)
	(paper "A4")
	(title_block
		(title "03242023_DA0F0TMBIJ0_F0T_Motherboard_J_brd_V01_OCP.brd")
		(comment 1 "Grand Teton / footprints 5327-5329 of 6105")
	)
	(layers
		(0 "F.Cu" signal "TOP")
		(4 "In1.Cu" signal "GND")
		(6 "In2.Cu" signal "IN1")
		(8 "In3.Cu" signal "GND1")
		(10 "In4.Cu" signal "IN2")
		(12 "In5.Cu" signal "GND2")
		(14 "In6.Cu" signal "IN3")
		(16 "In7.Cu" signal "GND3")
		(18 "In8.Cu" signal "VCC")
		(20 "In9.Cu" signal "VCC1")
		(22 "In10.Cu" signal "GND4")
		(24 "In11.Cu" signal "IN4")
		(26 "In12.Cu" signal "GND5")
		(28 "In13.Cu" signal "IN5")
		(30 "In14.Cu" signal "GND6")
		(32 "In15.Cu" signal "IN6")
		(34 "In16.Cu" signal "GND7")
		(2 "B.Cu" signal "BOTTOM")
		(9 "F.Adhes" user "F.Adhesive")
		(11 "B.Adhes" user "B.Adhesive")
		(13 "F.Paste" user "Package Geometry/Pastemask Top")
		(15 "B.Paste" user "Package Geometry/Pastemask Bottom")
		(5 "F.SilkS" user "Ref Des/Silkscreen Top")
		(7 "B.SilkS" user "Ref Des/Silkscreen Bottom")
		(1 "F.Mask" user "Board Geometry/Soldermask Top")
		(3 "B.Mask" user "Board Geometry/Soldermask Bottom")
		(17 "Dwgs.User" user "User.Drawings")
		(19 "Cmts.User" user "User.Comments")
		(21 "Eco1.User" user "User.Eco1")
		(23 "Eco2.User" user "User.Eco2")
		(25 "Edge.Cuts" user "Board Geometry/Outline")
		(27 "Margin" user)
		(31 "F.CrtYd" user "Package Geometry/Place Bound Top")
		(29 "B.CrtYd" user "Package Geometry/Place Bound Bottom")
		(35 "F.Fab" user "Ref Des/Assembly Top")
		(33 "B.Fab" user "Ref Des/Assembly Bottom")
	)
	(footprint ""
		(layer "B.Cu")
		(at 422.218104 -137.658094 -90)
		(property "Reference" "PR436"
			(at 0 0 90)
			(layer "B.SilkS")
			(hide yes)
			(effects
				(font
					(size 1.27 1.27)
				)
				(justify mirror)
			)
		)
		(property "Value" ""
			(at 0 0 90)
			(layer "B.Fab")
			(effects
				(font
					(size 1.27 1.27)
				)
				(justify mirror)
			)
		)
		(duplicate_pad_numbers_are_jumpers no)
		(fp_line
			(start -0.7874 0.4064)
			(end 0.7874 0.4064)
			(stroke
				(width 0.1524)
				(type default)
			)
			(layer "B.SilkS")
		)
		(fp_line
			(start 0.7874 0.4064)
			(end 0.7874 -0.4064)
			(stroke
				(width 0.1524)
				(type default)
			)
			(layer "B.SilkS")
		)
		(fp_line
			(start -0.7874 -0.4064)
			(end -0.7874 0.4064)
			(stroke
				(width 0.1524)
				(type default)
			)
			(layer "B.SilkS")
		)
		(fp_line
			(start 0.7874 -0.4064)
			(end -0.7874 -0.4064)
			(stroke
				(width 0.1524)
				(type default)
			)
			(layer "B.SilkS")
		)
		(fp_line
			(start -0.67945 0.3048)
			(end -0.120396 0.3048)
			(stroke
				(width 0.1)
				(type default)
			)
			(layer "B.Fab")
		)
		(fp_line
			(start -0.120396 0.3048)
			(end -0.120396 0.2794)
			(stroke
				(width 0.1)
				(type default)
			)
			(layer "B.Fab")
		)
		(fp_line
			(start 0.12065 0.3048)
			(end 0.67945 0.3048)
			(stroke
				(width 0.1)
				(type default)
			)
			(layer "B.Fab")
		)
		(fp_line
			(start 0.67945 0.3048)
			(end 0.67945 -0.305054)
			(stroke
				(width 0.1)
				(type default)
			)
			(layer "B.Fab")
		)
		(fp_line
			(start -0.120396 0.2794)
			(end 0.12065 0.2794)
			(stroke
				(width 0.1)
				(type default)
			)
			(layer "B.Fab")
		)
		(fp_line
			(start 0.12065 0.2794)
			(end 0.12065 0.3048)
			(stroke
				(width 0.1)
				(type default)
			)
			(layer "B.Fab")
		)
		(fp_line
			(start -0.12065 -0.2794)
			(end -0.12065 -0.3048)
			(stroke
				(width 0.1)
				(type default)
			)
			(layer "B.Fab")
		)
		(fp_line
			(start 0.12065 -0.2794)
			(end -0.12065 -0.2794)
			(stroke
				(width 0.1)
				(type default)
			)
			(layer "B.Fab")
		)
		(fp_line
			(start -0.67945 -0.3048)
			(end -0.67945 0.3048)
			(stroke
				(width 0.1)
				(type default)
			)
			(layer "B.Fab")
		)
		(fp_line
			(start -0.12065 -0.3048)
			(end -0.67945 -0.3048)
			(stroke
				(width 0.1)
				(type default)
			)
			(layer "B.Fab")
		)
		(fp_line
			(start 0.12065 -0.305054)
			(end 0.12065 -0.2794)
			(stroke
				(width 0.1)
				(type default)
			)
			(layer "B.Fab")
		)
		(fp_line
			(start 0.67945 -0.305054)
			(end 0.12065 -0.305054)
			(stroke
				(width 0.1)
				(type default)
			)
			(layer "B.Fab")
		)
		(pad "1" smd circle
			(at 0.40005 0 90)
			(size 0 0)
			(layers "B.Cu" "B.Mask" "B.Paste")
			(net "PVCCFA_EHV_CPU0_BTSEN")
		)
		(pad "2" smd circle
			(at -0.40005 0 90)
			(size 0 0)
			(layers "B.Cu" "B.Mask" "B.Paste")
			(net "GND")
		)
	)
	(footprint ""
		(layer "B.Cu")
		(at 41.830244 -99.75723 -90)
		(property "Reference" "R3939"
			(at 0 0 90)
			(layer "B.SilkS")
			(hide yes)
			(effects
				(font
					(size 1.27 1.27)
				)
				(justify mirror)
			)
		)
		(property "Value" ""
			(at 0 0 90)
			(layer "B.Fab")
			(effects
				(font
					(size 1.27 1.27)
				)
				(justify mirror)
			)
		)
		(duplicate_pad_numbers_are_jumpers no)
		(fp_line
			(start -0.7874 0.4064)
			(end 0.7874 0.4064)
			(stroke
				(width 0.1524)
				(type default)
			)
			(layer "B.SilkS")
		)
		(fp_line
			(start 0.7874 0.4064)
			(end 0.7874 -0.4064)
			(stroke
				(width 0.1524)
				(type default)
			)
			(layer "B.SilkS")
		)
		(fp_line
			(start -0.7874 -0.4064)
			(end -0.7874 0.4064)
			(stroke
				(width 0.1524)
				(type default)
			)
			(layer "B.SilkS")
		)
		(fp_line
			(start 0.7874 -0.4064)
			(end -0.7874 -0.4064)
			(stroke
				(width 0.1524)
				(type default)
			)
			(layer "B.SilkS")
		)
		(fp_line
			(start -0.67945 0.3048)
			(end -0.120396 0.3048)
			(stroke
				(width 0.1)
				(type default)
			)
			(layer "B.Fab")
		)
		(fp_line
			(start -0.120396 0.3048)
			(end -0.120396 0.2794)
			(stroke
				(width 0.1)
				(type default)
			)
			(layer "B.Fab")
		)
		(fp_line
			(start 0.12065 0.3048)
			(end 0.67945 0.3048)
			(stroke
				(width 0.1)
				(type default)
			)
			(layer "B.Fab")
		)
		(fp_line
			(start 0.67945 0.3048)
			(end 0.67945 -0.305054)
			(stroke
				(width 0.1)
				(type default)
			)
			(layer "B.Fab")
		)
		(fp_line
			(start -0.120396 0.2794)
			(end 0.12065 0.2794)
			(stroke
				(width 0.1)
				(type default)
			)
			(layer "B.Fab")
		)
		(fp_line
			(start 0.12065 0.2794)
			(end 0.12065 0.3048)
			(stroke
				(width 0.1)
				(type default)
			)
			(layer "B.Fab")
		)
		(fp_line
			(start -0.12065 -0.2794)
			(end -0.12065 -0.3048)
			(stroke
				(width 0.1)
				(type default)
			)
			(layer "B.Fab")
		)
		(fp_line
			(start 0.12065 -0.2794)
			(end -0.12065 -0.2794)
			(stroke
				(width 0.1)
				(type default)
			)
			(layer "B.Fab")
		)
		(fp_line
			(start -0.67945 -0.3048)
			(end -0.67945 0.3048)
			(stroke
				(width 0.1)
				(type default)
			)
			(layer "B.Fab")
		)
		(fp_line
			(start -0.12065 -0.3048)
			(end -0.67945 -0.3048)
			(stroke
				(width 0.1)
				(type default)
			)
			(layer "B.Fab")
		)
		(fp_line
			(start 0.12065 -0.305054)
			(end 0.12065 -0.2794)
			(stroke
				(width 0.1)
				(type default)
			)
			(layer "B.Fab")
		)
		(fp_line
			(start 0.67945 -0.305054)
			(end 0.12065 -0.305054)
			(stroke
				(width 0.1)
				(type default)
			)
			(layer "B.Fab")
		)
		(pad "1" smd rect
			(at 0.40005 0 270)
			(size 0.4572 0.508)
			(layers "B.Cu" "B.Mask" "B.Paste")
			(net "P12V_E1S_0_ISENSE_MAM_MAM")
		)
		(pad "2" smd rect
			(at -0.40005 0 270)
			(size 0.4572 0.508)
			(layers "B.Cu" "B.Mask" "B.Paste")
			(net "P12V_E1S_0_ISENSE_MAM")
		)
	)
	(footprint ""
		(layer "B.Cu")
		(at 407.91257 -158.714948 180)
		(property "Reference" "PC1"
			(at 0 0 0)
			(layer "B.SilkS")
			(hide yes)
			(effects
				(font
					(size 1.27 1.27)
				)
				(justify mirror)
			)
		)
		(property "Value" ""
			(at 0 0 0)
			(layer "B.Fab")
			(effects
				(font
					(size 1.27 1.27)
				)
				(justify mirror)
			)
		)
		(duplicate_pad_numbers_are_jumpers no)
		(fp_line
			(start 1.524 0.762)
			(end 1.524 -0.762)
			(stroke
				(width 0.1524)
				(type default)
			)
			(layer "B.SilkS")
		)
		(fp_line
			(start 1.524 -0.762)
			(end -1.524 -0.762)
			(stroke
				(width 0.1524)
				(type default)
			)
			(layer "B.SilkS")
		)
		(fp_line
			(start -1.524 0.762)
			(end 1.524 0.762)
			(stroke
				(width 0.1524)
				(type default)
			)
			(layer "B.SilkS")
		)
		(fp_line
			(start -1.524 -0.762)
			(end -1.524 0.762)
			(stroke
				(width 0.1524)
				(type default)
			)
			(layer "B.SilkS")
		)
		(fp_line
			(start 1.1049 0.724916)
			(end -1.1049 0.724916)
			(stroke
				(width 0.1)
				(type default)
			)
			(layer "B.Fab")
		)
		(fp_line
			(start 1.1049 -0.724916)
			(end 1.1049 0.724916)
			(stroke
				(width 0.1)
				(type default)
			)
			(layer "B.Fab")
		)
		(fp_line
			(start -1.1049 0.724916)
			(end -1.1049 -0.724916)
			(stroke
				(width 0.1)
				(type default)
			)
			(layer "B.Fab")
		)
		(fp_line
			(start -1.1049 -0.724916)
			(end 1.1049 -0.724916)
			(stroke
				(width 0.1)
				(type default)
			)
			(layer "B.Fab")
		)
		(pad "1" smd rect
			(at 0.889 0 180)
			(size 1.016 1.27)
			(layers "B.Cu" "B.Mask" "B.Paste")
			(net "PVCCD_HV_CPU0")
		)
		(pad "2" smd rect
			(at -0.889 0 180)
			(size 1.016 1.27)
			(layers "B.Cu" "B.Mask" "B.Paste")
			(net "GND")
		)
	)
)
